# S9S_MB_2U (Grand Teton) — schematic netlist excerpt (pin names and nets, part order shuffled) for the footprints in the layout excerpt that follows; sources: Cadence DE-HDL packaged netlist, KiCad conversion of 03242023_DA0F0TMBIJ0_F0T_Motherboard_J_brd_V01_OCP.brd

R3527  Q_RES  0 5% CHIP  pkg 0402LF  page 231 : A = SMB_PCIE0_3V3AUX_SDA_R5 ; B = SMB_SENSOR_E1S_3V3AUX_SDA
R749  Q_RES  75 1% CHIP  pkg 0402LF  page 132 : A = P1V05_PCH_AUX ; B = JTAG_DBP_TMS_PCH

(kicad_pcb
	(version 20260206)
	(generator "pcbnew")
	(generator_version "10.0")
	(general
		(thickness 1.6)
		(legacy_teardrops no)
	)
	(paper "A4")
	(title_block
		(title "03242023_DA0F0TMBIJ0_F0T_Motherboard_J_brd_V01_OCP.brd")
		(comment 1 "Grand Teton / footprints 3381-3382 of 6105")
	)
	(layers
		(0 "F.Cu" signal "TOP")
		(4 "In1.Cu" signal "GND")
		(6 "In2.Cu" signal "IN1")
		(8 "In3.Cu" signal "GND1")
		(10 "In4.Cu" signal "IN2")
		(12 "In5.Cu" signal "GND2")
		(14 "In6.Cu" signal "IN3")
		(16 "In7.Cu" signal "GND3")
		(18 "In8.Cu" signal "VCC")
		(20 "In9.Cu" signal "VCC1")
		(22 "In10.Cu" signal "GND4")
		(24 "In11.Cu" signal "IN4")
		(26 "In12.Cu" signal "GND5")
		(28 "In13.Cu" signal "IN5")
		(30 "In14.Cu" signal "GND6")
		(32 "In15.Cu" signal "IN6")
		(34 "In16.Cu" signal "GND7")
		(2 "B.Cu" signal "BOTTOM")
		(9 "F.Adhes" user "F.Adhesive")
		(11 "B.Adhes" user "B.Adhesive")
		(13 "F.Paste" user "Package Geometry/Pastemask Top")
		(15 "B.Paste" user "Package Geometry/Pastemask Bottom")
		(5 "F.SilkS" user "Ref Des/Silkscreen Top")
		(7 "B.SilkS" user "Ref Des/Silkscreen Bottom")
		(1 "F.Mask" user "Board Geometry/Soldermask Top")
		(3 "B.Mask" user "Board Geometry/Soldermask Bottom")
		(17 "Dwgs.User" user "User.Drawings")
		(19 "Cmts.User" user "User.Comments")
		(21 "Eco1.User" user "User.Eco1")
		(23 "Eco2.User" user "User.Eco2")
		(25 "Edge.Cuts" user "Board Geometry/Outline")
		(27 "Margin" user)
		(31 "F.CrtYd" user "Package Geometry/Place Bound Top")
		(29 "B.CrtYd" user "Package Geometry/Place Bound Bottom")
		(35 "F.Fab" user "Ref Des/Assembly Top")
		(33 "B.Fab" user "Ref Des/Assembly Bottom")
	)
	(footprint ""
		(layer "F.Cu")
		(at 113.494312 -129.408682 180)
		(property "Reference" "R3527"
			(at 0 0 180)
			(layer "F.SilkS")
			(hide yes)
			(effects
				(font
					(size 1.27 1.27)
				)
			)
		)
		(property "Value" ""
			(at 0 0 180)
			(layer "F.Fab")
			(effects
				(font
					(size 1.27 1.27)
				)
			)
		)
		(duplicate_pad_numbers_are_jumpers no)
		(fp_line
			(start 0.7874 0.4064)
			(end -0.7874 0.4064)
			(stroke
				(width 0.1524)
				(type default)
			)
			(layer "F.SilkS")
		)
		(fp_line
			(start 0.7874 -0.4064)
			(end 0.7874 0.4064)
			(stroke
				(width 0.1524)
				(type default)
			)
			(layer "F.SilkS")
		)
		(fp_line
			(start -0.7874 0.4064)
			(end -0.7874 -0.4064)
			(stroke
				(width 0.1524)
				(type default)
			)
			(layer "F.SilkS")
		)
		(fp_line
			(start -0.7874 -0.4064)
			(end 0.7874 -0.4064)
			(stroke
				(width 0.1524)
				(type default)
			)
			(layer "F.SilkS")
		)
		(fp_line
			(start 0.67945 0.3048)
			(end 0.120396 0.3048)
			(stroke
				(width 0.1)
				(type default)
			)
			(layer "F.Fab")
		)
		(fp_line
			(start 0.67945 -0.3048)
			(end 0.67945 0.3048)
			(stroke
				(width 0.1)
				(type default)
			)
			(layer "F.Fab")
		)
		(fp_line
			(start 0.12065 -0.2794)
			(end 0.12065 -0.3048)
			(stroke
				(width 0.1)
				(type default)
			)
			(layer "F.Fab")
		)
		(fp_line
			(start 0.12065 -0.3048)
			(end 0.67945 -0.3048)
			(stroke
				(width 0.1)
				(type default)
			)
			(layer "F.Fab")
		)
		(fp_line
			(start 0.120396 0.3048)
			(end 0.120396 0.2794)
			(stroke
				(width 0.1)
				(type default)
			)
			(layer "F.Fab")
		)
		(fp_line
			(start 0.120396 0.2794)
			(end -0.12065 0.2794)
			(stroke
				(width 0.1)
				(type default)
			)
			(layer "F.Fab")
		)
		(fp_line
			(start -0.12065 0.3048)
			(end -0.67945 0.3048)
			(stroke
				(width 0.1)
				(type default)
			)
			(layer "F.Fab")
		)
		(fp_line
			(start -0.12065 0.2794)
			(end -0.12065 0.3048)
			(stroke
				(width 0.1)
				(type default)
			)
			(layer "F.Fab")
		)
		(fp_line
			(start -0.12065 -0.2794)
			(end 0.12065 -0.2794)
			(stroke
				(width 0.1)
				(type default)
			)
			(layer "F.Fab")
		)
		(fp_line
			(start -0.12065 -0.305054)
			(end -0.12065 -0.2794)
			(stroke
				(width 0.1)
				(type default)
			)
			(layer "F.Fab")
		)
		(fp_line
			(start -0.67945 0.3048)
			(end -0.67945 -0.305054)
			(stroke
				(width 0.1)
				(type default)
			)
			(layer "F.Fab")
		)
		(fp_line
			(start -0.67945 -0.305054)
			(end -0.12065 -0.305054)
			(stroke
				(width 0.1)
				(type default)
			)
			(layer "F.Fab")
		)
		(pad "1" smd circle
			(at -0.40005 0 180)
			(size 0 0)
			(layers "F.Cu" "F.Mask" "F.Paste")
			(net "SMB_PCIE0_3V3AUX_SDA_R5")
		)
		(pad "2" smd circle
			(at 0.40005 0 180)
			(size 0 0)
			(layers "F.Cu" "F.Mask" "F.Paste")
			(net "SMB_SENSOR_E1S_3V3AUX_SDA")
		)
	)
	(footprint ""
		(layer "F.Cu")
		(at 367.411 -53.812948)
		(property "Reference" "R749"
			(at 0 0 0)
			(layer "F.SilkS")
			(hide yes)
			(effects
				(font
					(size 1.27 1.27)
				)
			)
		)
		(property "Value" ""
			(at 0 0 0)
			(layer "F.Fab")
			(effects
				(font
					(size 1.27 1.27)
				)
			)
		)
		(duplicate_pad_numbers_are_jumpers no)
		(fp_line
			(start -0.7874 -0.4064)
			(end 0.7874 -0.4064)
			(stroke
				(width 0.1524)
				(type default)
			)
			(layer "F.SilkS")
		)
		(fp_line
			(start -0.7874 0.4064)
			(end -0.7874 -0.4064)
			(stroke
				(width 0.1524)
				(type default)
			)
			(layer "F.SilkS")
		)
		(fp_line
			(start 0.7874 -0.4064)
			(end 0.7874 0.4064)
			(stroke
				(width 0.1524)
				(type default)
			)
			(layer "F.SilkS")
		)
		(fp_line
			(start 0.7874 0.4064)
			(end -0.7874 0.4064)
			(stroke
				(width 0.1524)
				(type default)
			)
			(layer "F.SilkS")
		)
		(fp_line
			(start -0.67945 -0.305054)
			(end -0.12065 -0.305054)
			(stroke
				(width 0.1)
				(type default)
			)
			(layer "F.Fab")
		)
		(fp_line
			(start -0.67945 0.3048)
			(end -0.67945 -0.305054)
			(stroke
				(width 0.1)
				(type default)
			)
			(layer "F.Fab")
		)
		(fp_line
			(start -0.12065 -0.305054)
			(end -0.12065 -0.2794)
			(stroke
				(width 0.1)
				(type default)
			)
			(layer "F.Fab")
		)
		(fp_line
			(start -0.12065 -0.2794)
			(end 0.12065 -0.2794)
			(stroke
				(width 0.1)
				(type default)
			)
			(layer "F.Fab")
		)
		(fp_line
			(start -0.12065 0.2794)
			(end -0.12065 0.3048)
			(stroke
				(width 0.1)
				(type default)
			)
			(layer "F.Fab")
		)
		(fp_line
			(start -0.12065 0.3048)
			(end -0.67945 0.3048)
			(stroke
				(width 0.1)
				(type default)
			)
			(layer "F.Fab")
		)
		(fp_line
			(start 0.120396 0.2794)
			(end -0.12065 0.2794)
			(stroke
				(width 0.1)
				(type default)
			)
			(layer "F.Fab")
		)
		(fp_line
			(start 0.120396 0.3048)
			(end 0.120396 0.2794)
			(stroke
				(width 0.1)
				(type default)
			)
			(layer "F.Fab")
		)
		(fp_line
			(start 0.12065 -0.3048)
			(end 0.67945 -0.3048)
			(stroke
				(width 0.1)
				(type default)
			)
			(layer "F.Fab")
		)
		(fp_line
			(start 0.12065 -0.2794)
			(end 0.12065 -0.3048)
			(stroke
				(width 0.1)
				(type default)
			)
			(layer "F.Fab")
		)
		(fp_line
			(start 0.67945 -0.3048)
			(end 0.67945 0.3048)
			(stroke
				(width 0.1)
				(type default)
			)
			(layer "F.Fab")
		)
		(fp_line
			(start 0.67945 0.3048)
			(end 0.120396 0.3048)
			(stroke
				(width 0.1)
				(type default)
			)
			(layer "F.Fab")
		)
		(pad "1" smd circle
			(at -0.40005 0)
			(size 0 0)
			(layers "F.Cu" "F.Mask" "F.Paste")
			(net "P1V05_PCH_AUX")
		)
		(pad "2" smd circle
			(at 0.40005 0)
			(size 0 0)
			(layers "F.Cu" "F.Mask" "F.Paste")
			(net "JTAG_DBP_TMS_PCH")
		)
	)
)
